(kicad_pcb
	(version 20260206)
	(generator "pcbnew")
	(generator_version "10.0")
	(general
		(thickness 1.6)
		(legacy_teardrops no)
	)
	(paper "A4")
	(title_block
		(title "01162023_DA0F0TEBIF0_F0T_Expander_BD_F_brd_V02_OCP.brd")
		(comment 1 "Grand Teton / footprints 4394-4400 of 9728")
	)
	(layers
		(0 "F.Cu" signal "TOP")
		(4 "In1.Cu" signal "GND")
		(6 "In2.Cu" signal "VCC")
		(8 "In3.Cu" signal "VCC1")
		(10 "In4.Cu" signal "GND1")
		(12 "In5.Cu" signal "IN1")
		(14 "In6.Cu" signal "GND2")
		(16 "In7.Cu" signal "IN2")
		(18 "In8.Cu" signal "GND3")
		(20 "In9.Cu" signal "IN3")
		(22 "In10.Cu" signal "GND4")
		(24 "In11.Cu" signal "IN4")
		(26 "In12.Cu" signal "GND5")
		(28 "In13.Cu" signal "IN5")
		(30 "In14.Cu" signal "GND6")
		(32 "In15.Cu" signal "IN6")
		(34 "In16.Cu" signal "GND7")
		(2 "B.Cu" signal "BOTTOM")
		(9 "F.Adhes" user "F.Adhesive")
		(11 "B.Adhes" user "B.Adhesive")
		(13 "F.Paste" user "Package Geometry/Pastemask Top")
		(15 "B.Paste" user "Package Geometry/Pastemask Bottom")
		(5 "F.SilkS" user "Ref Des/Silkscreen Top")
		(7 "B.SilkS" user "Ref Des/Silkscreen Bottom")
		(1 "F.Mask" user "Board Geometry/Soldermask Top")
		(3 "B.Mask" user "Board Geometry/Soldermask Bottom")
		(17 "Dwgs.User" user "User.Drawings")
		(19 "Cmts.User" user "User.Comments")
		(21 "Eco1.User" user "User.Eco1")
		(23 "Eco2.User" user "User.Eco2")
		(25 "Edge.Cuts" user "Board Geometry/Outline")
		(27 "Margin" user)
		(31 "F.CrtYd" user "Package Geometry/Place Bound Top")
		(29 "B.CrtYd" user "Package Geometry/Place Bound Bottom")
		(35 "F.Fab" user "Ref Des/Assembly Top")
		(33 "B.Fab" user "Ref Des/Assembly Bottom")
	)
	(footprint ""
		(layer "F.Cu")
		(at 363.474 -210.947)
		(property "Reference" "R4598"
			(at 0 0 0)
			(layer "F.SilkS")
			(hide yes)
			(effects
				(font
					(size 1.27 1.27)
				)
			)
		)
		(property "Value" ""
			(at 0 0 0)
			(layer "F.Fab")
			(effects
				(font
					(size 1.27 1.27)
				)
			)
		)
		(duplicate_pad_numbers_are_jumpers no)
		(fp_line
			(start -0.7874 -0.4064)
			(end 0.7874 -0.4064)
			(stroke
				(width 0.1524)
				(type default)
			)
			(layer "F.SilkS")
		)
		(fp_line
			(start -0.7874 0.4064)
			(end -0.7874 -0.4064)
			(stroke
				(width 0.1524)
				(type default)
			)
			(layer "F.SilkS")
		)
		(fp_line
			(start 0.7874 -0.4064)
			(end 0.7874 0.4064)
			(stroke
				(width 0.1524)
				(type default)
			)
			(layer "F.SilkS")
		)
		(fp_line
			(start 0.7874 0.4064)
			(end -0.7874 0.4064)
			(stroke
				(width 0.1524)
				(type default)
			)
			(layer "F.SilkS")
		)
		(fp_line
			(start -0.67945 -0.305054)
			(end -0.12065 -0.305054)
			(stroke
				(width 0.1)
				(type default)
			)
			(layer "F.Fab")
		)
		(fp_line
			(start -0.67945 0.3048)
			(end -0.67945 -0.305054)
			(stroke
				(width 0.1)
				(type default)
			)
			(layer "F.Fab")
		)
		(fp_line
			(start -0.12065 -0.305054)
			(end -0.12065 -0.2794)
			(stroke
				(width 0.1)
				(type default)
			)
			(layer "F.Fab")
		)
		(fp_line
			(start -0.12065 -0.2794)
			(end 0.12065 -0.2794)
			(stroke
				(width 0.1)
				(type default)
			)
			(layer "F.Fab")
		)
		(fp_line
			(start -0.12065 0.2794)
			(end -0.12065 0.3048)
			(stroke
				(width 0.1)
				(type default)
			)
			(layer "F.Fab")
		)
		(fp_line
			(start -0.12065 0.3048)
			(end -0.67945 0.3048)
			(stroke
				(width 0.1)
				(type default)
			)
			(layer "F.Fab")
		)
		(fp_line
			(start 0.120396 0.2794)
			(end -0.12065 0.2794)
			(stroke
				(width 0.1)
				(type default)
			)
			(layer "F.Fab")
		)
		(fp_line
			(start 0.120396 0.3048)
			(end 0.120396 0.2794)
			(stroke
				(width 0.1)
				(type default)
			)
			(layer "F.Fab")
		)
		(fp_line
			(start 0.12065 -0.3048)
			(end 0.67945 -0.3048)
			(stroke
				(width 0.1)
				(type default)
			)
			(layer "F.Fab")
		)
		(fp_line
			(start 0.12065 -0.2794)
			(end 0.12065 -0.3048)
			(stroke
				(width 0.1)
				(type default)
			)
			(layer "F.Fab")
		)
		(fp_line
			(start 0.67945 -0.3048)
			(end 0.67945 0.3048)
			(stroke
				(width 0.1)
				(type default)
			)
			(layer "F.Fab")
		)
		(fp_line
			(start 0.67945 0.3048)
			(end 0.120396 0.3048)
			(stroke
				(width 0.1)
				(type default)
			)
			(layer "F.Fab")
		)
		(pad "1" smd circle
			(at -0.40005 0)
			(size 0 0)
			(layers "F.Cu" "F.Mask" "F.Paste")
			(net "P3V3_AUX")
		)
		(pad "2" smd circle
			(at 0.40005 0)
			(size 0 0)
			(layers "F.Cu" "F.Mask" "F.Paste")
			(net "SSD0_PEX_PWR_EN_R")
		)
	)
	(footprint ""
		(layer "F.Cu")
		(at 186.789568 -406.59431 90)
		(property "Reference" "R4417"
			(at 0 0 90)
			(layer "F.SilkS")
			(hide yes)
			(effects
				(font
					(size 1.27 1.27)
				)
			)
		)
		(property "Value" ""
			(at 0 0 90)
			(layer "F.Fab")
			(effects
				(font
					(size 1.27 1.27)
				)
			)
		)
		(duplicate_pad_numbers_are_jumpers no)
		(fp_line
			(start 0.7874 -0.4064)
			(end 0.7874 0.4064)
			(stroke
				(width 0.1524)
				(type default)
			)
			(layer "F.SilkS")
		)
		(fp_line
			(start -0.7874 -0.4064)
			(end 0.7874 -0.4064)
			(stroke
				(width 0.1524)
				(type default)
			)
			(layer "F.SilkS")
		)
		(fp_line
			(start 0.7874 0.4064)
			(end -0.7874 0.4064)
			(stroke
				(width 0.1524)
				(type default)
			)
			(layer "F.SilkS")
		)
		(fp_line
			(start -0.7874 0.4064)
			(end -0.7874 -0.4064)
			(stroke
				(width 0.1524)
				(type default)
			)
			(layer "F.SilkS")
		)
		(fp_line
			(start -0.12065 -0.305054)
			(end -0.12065 -0.2794)
			(stroke
				(width 0.1)
				(type default)
			)
			(layer "F.Fab")
		)
		(fp_line
			(start -0.67945 -0.305054)
			(end -0.12065 -0.305054)
			(stroke
				(width 0.1)
				(type default)
			)
			(layer "F.Fab")
		)
		(fp_line
			(start 0.67945 -0.3048)
			(end 0.67945 0.3048)
			(stroke
				(width 0.1)
				(type default)
			)
			(layer "F.Fab")
		)
		(fp_line
			(start 0.12065 -0.3048)
			(end 0.67945 -0.3048)
			(stroke
				(width 0.1)
				(type default)
			)
			(layer "F.Fab")
		)
		(fp_line
			(start 0.12065 -0.2794)
			(end 0.12065 -0.3048)
			(stroke
				(width 0.1)
				(type default)
			)
			(layer "F.Fab")
		)
		(fp_line
			(start -0.12065 -0.2794)
			(end 0.12065 -0.2794)
			(stroke
				(width 0.1)
				(type default)
			)
			(layer "F.Fab")
		)
		(fp_line
			(start 0.120396 0.2794)
			(end -0.12065 0.2794)
			(stroke
				(width 0.1)
				(type default)
			)
			(layer "F.Fab")
		)
		(fp_line
			(start -0.12065 0.2794)
			(end -0.12065 0.3048)
			(stroke
				(width 0.1)
				(type default)
			)
			(layer "F.Fab")
		)
		(fp_line
			(start 0.67945 0.3048)
			(end 0.120396 0.3048)
			(stroke
				(width 0.1)
				(type default)
			)
			(layer "F.Fab")
		)
		(fp_line
			(start 0.120396 0.3048)
			(end 0.120396 0.2794)
			(stroke
				(width 0.1)
				(type default)
			)
			(layer "F.Fab")
		)
		(fp_line
			(start -0.12065 0.3048)
			(end -0.67945 0.3048)
			(stroke
				(width 0.1)
				(type default)
			)
			(layer "F.Fab")
		)
		(fp_line
			(start -0.67945 0.3048)
			(end -0.67945 -0.305054)
			(stroke
				(width 0.1)
				(type default)
			)
			(layer "F.Fab")
		)
		(pad "1" smd circle
			(at -0.40005 0 90)
			(size 0 0)
			(layers "F.Cu" "F.Mask" "F.Paste")
			(net "FM_UV_ADR_TRIGGER_N")
		)
		(pad "2" smd circle
			(at 0.40005 0 90)
			(size 0 0)
			(layers "F.Cu" "F.Mask" "F.Paste")
			(net "P3V3_AUX")
		)
	)
	(footprint ""
		(layer "F.Cu")
		(at 376.312684 -83.1088)
		(property "Reference" "R1748"
			(at 0 0 0)
			(layer "F.SilkS")
			(hide yes)
			(effects
				(font
					(size 1.27 1.27)
				)
			)
		)
		(property "Value" ""
			(at 0 0 0)
			(layer "F.Fab")
			(effects
				(font
					(size 1.27 1.27)
				)
			)
		)
		(duplicate_pad_numbers_are_jumpers no)
		(fp_line
			(start -0.7874 -0.4064)
			(end 0.7874 -0.4064)
			(stroke
				(width 0.1524)
				(type default)
			)
			(layer "F.SilkS")
		)
		(fp_line
			(start -0.7874 0.4064)
			(end -0.7874 -0.4064)
			(stroke
				(width 0.1524)
				(type default)
			)
			(layer "F.SilkS")
		)
		(fp_line
			(start 0.7874 -0.4064)
			(end 0.7874 0.4064)
			(stroke
				(width 0.1524)
				(type default)
			)
			(layer "F.SilkS")
		)
		(fp_line
			(start 0.7874 0.4064)
			(end -0.7874 0.4064)
			(stroke
				(width 0.1524)
				(type default)
			)
			(layer "F.SilkS")
		)
		(fp_line
			(start -0.67945 -0.305054)
			(end -0.12065 -0.305054)
			(stroke
				(width 0.1)
				(type default)
			)
			(layer "F.Fab")
		)
		(fp_line
			(start -0.67945 0.3048)
			(end -0.67945 -0.305054)
			(stroke
				(width 0.1)
				(type default)
			)
			(layer "F.Fab")
		)
		(fp_line
			(start -0.12065 -0.305054)
			(end -0.12065 -0.2794)
			(stroke
				(width 0.1)
				(type default)
			)
			(layer "F.Fab")
		)
		(fp_line
			(start -0.12065 -0.2794)
			(end 0.12065 -0.2794)
			(stroke
				(width 0.1)
				(type default)
			)
			(layer "F.Fab")
		)
		(fp_line
			(start -0.12065 0.2794)
			(end -0.12065 0.3048)
			(stroke
				(width 0.1)
				(type default)
			)
			(layer "F.Fab")
		)
		(fp_line
			(start -0.12065 0.3048)
			(end -0.67945 0.3048)
			(stroke
				(width 0.1)
				(type default)
			)
			(layer "F.Fab")
		)
		(fp_line
			(start 0.120396 0.2794)
			(end -0.12065 0.2794)
			(stroke
				(width 0.1)
				(type default)
			)
			(layer "F.Fab")
		)
		(fp_line
			(start 0.120396 0.3048)
			(end 0.120396 0.2794)
			(stroke
				(width 0.1)
				(type default)
			)
			(layer "F.Fab")
		)
		(fp_line
			(start 0.12065 -0.3048)
			(end 0.67945 -0.3048)
			(stroke
				(width 0.1)
				(type default)
			)
			(layer "F.Fab")
		)
		(fp_line
			(start 0.12065 -0.2794)
			(end 0.12065 -0.3048)
			(stroke
				(width 0.1)
				(type default)
			)
			(layer "F.Fab")
		)
		(fp_line
			(start 0.67945 -0.3048)
			(end 0.67945 0.3048)
			(stroke
				(width 0.1)
				(type default)
			)
			(layer "F.Fab")
		)
		(fp_line
			(start 0.67945 0.3048)
			(end 0.120396 0.3048)
			(stroke
				(width 0.1)
				(type default)
			)
			(layer "F.Fab")
		)
		(pad "1" smd circle
			(at -0.40005 0)
			(size 0 0)
			(layers "F.Cu" "F.Mask" "F.Paste")
			(net "P3V3_AUX")
		)
		(pad "2" smd circle
			(at 0.40005 0)
			(size 0 0)
			(layers "F.Cu" "F.Mask" "F.Paste")
			(net "SMB_BIC_I2C6_MUX_THERMAL_R_SCL")
		)
	)
	(footprint ""
		(layer "F.Cu")
		(at 313.391804 -350.098614 90)
		(property "Reference" "C550"
			(at 0 0 90)
			(layer "F.SilkS")
			(hide yes)
			(effects
				(font
					(size 1.27 1.27)
				)
			)
		)
		(property "Value" ""
			(at 0 0 90)
			(layer "F.Fab")
			(effects
				(font
					(size 1.27 1.27)
				)
			)
		)
		(duplicate_pad_numbers_are_jumpers no)
		(fp_line
			(start 0.299974 -0.150114)
			(end 0.299974 0.150114)
			(stroke
				(width 0.1)
				(type default)
			)
			(layer "F.Fab")
		)
		(fp_line
			(start -0.299974 -0.150114)
			(end 0.299974 -0.150114)
			(stroke
				(width 0.1)
				(type default)
			)
			(layer "F.Fab")
		)
		(fp_line
			(start 0.299974 0.150114)
			(end -0.299974 0.150114)
			(stroke
				(width 0.1)
				(type default)
			)
			(layer "F.Fab")
		)
		(fp_line
			(start -0.299974 0.150114)
			(end -0.299974 -0.150114)
			(stroke
				(width 0.1)
				(type default)
			)
			(layer "F.Fab")
		)
		(pad "1" smd rect
			(at -0.2667 0 90)
			(size 0.3048 0.381)
			(layers "F.Cu" "F.Mask" "F.Paste")
			(net "P5E_PEX2_STN5_TX_DN<80>")
		)
		(pad "2" smd rect
			(at 0.2667 0 90)
			(size 0.3048 0.381)
			(layers "F.Cu" "F.Mask" "F.Paste")
			(net "P5E_PEX2_STN5_TX_C_DN<80>")
		)
	)
	(footprint ""
		(layer "F.Cu")
		(at 277.854664 -22.867366 90)
		(property "Reference" "C3937"
			(at 0 0 90)
			(layer "F.SilkS")
			(hide yes)
			(effects
				(font
					(size 1.27 1.27)
				)
			)
		)
		(property "Value" ""
			(at 0 0 90)
			(layer "F.Fab")
			(effects
				(font
					(size 1.27 1.27)
				)
			)
		)
		(duplicate_pad_numbers_are_jumpers no)
		(fp_line
			(start 0.7874 -0.4064)
			(end 0.7874 0.4064)
			(stroke
				(width 0.1524)
				(type default)
			)
			(layer "F.SilkS")
		)
		(fp_line
			(start -0.7874 -0.4064)
			(end 0.7874 -0.4064)
			(stroke
				(width 0.1524)
				(type default)
			)
			(layer "F.SilkS")
		)
		(fp_line
			(start 0.7874 0.4064)
			(end -0.7874 0.4064)
			(stroke
				(width 0.1524)
				(type default)
			)
			(layer "F.SilkS")
		)
		(fp_line
			(start -0.7874 0.4064)
			(end -0.7874 -0.4064)
			(stroke
				(width 0.1524)
				(type default)
			)
			(layer "F.SilkS")
		)
		(fp_line
			(start -0.12065 -0.305054)
			(end -0.12065 -0.2794)
			(stroke
				(width 0.1)
				(type default)
			)
			(layer "F.Fab")
		)
		(fp_line
			(start -0.67945 -0.305054)
			(end -0.12065 -0.305054)
			(stroke
				(width 0.1)
				(type default)
			)
			(layer "F.Fab")
		)
		(fp_line
			(start 0.67945 -0.3048)
			(end 0.67945 0.3048)
			(stroke
				(width 0.1)
				(type default)
			)
			(layer "F.Fab")
		)
		(fp_line
			(start 0.12065 -0.3048)
			(end 0.67945 -0.3048)
			(stroke
				(width 0.1)
				(type default)
			)
			(layer "F.Fab")
		)
		(fp_line
			(start 0.12065 -0.2794)
			(end 0.12065 -0.3048)
			(stroke
				(width 0.1)
				(type default)
			)
			(layer "F.Fab")
		)
		(fp_line
			(start -0.12065 -0.2794)
			(end 0.12065 -0.2794)
			(stroke
				(width 0.1)
				(type default)
			)
			(layer "F.Fab")
		)
		(fp_line
			(start 0.120396 0.2794)
			(end -0.12065 0.2794)
			(stroke
				(width 0.1)
				(type default)
			)
			(layer "F.Fab")
		)
		(fp_line
			(start -0.12065 0.2794)
			(end -0.12065 0.3048)
			(stroke
				(width 0.1)
				(type default)
			)
			(layer "F.Fab")
		)
		(fp_line
			(start 0.67945 0.3048)
			(end 0.120396 0.3048)
			(stroke
				(width 0.1)
				(type default)
			)
			(layer "F.Fab")
		)
		(fp_line
			(start 0.120396 0.3048)
			(end 0.120396 0.2794)
			(stroke
				(width 0.1)
				(type default)
			)
			(layer "F.Fab")
		)
		(fp_line
			(start -0.12065 0.3048)
			(end -0.67945 0.3048)
			(stroke
				(width 0.1)
				(type default)
			)
			(layer "F.Fab")
		)
		(fp_line
			(start -0.67945 0.3048)
			(end -0.67945 -0.305054)
			(stroke
				(width 0.1)
				(type default)
			)
			(layer "F.Fab")
		)
		(pad "1" smd circle
			(at -0.40005 0 90)
			(size 0 0)
			(layers "F.Cu" "F.Mask" "F.Paste")
			(net "P12V_SSD9")
		)
		(pad "2" smd circle
			(at 0.40005 0 90)
			(size 0 0)
			(layers "F.Cu" "F.Mask" "F.Paste")
			(net "GND")
		)
	)
	(footprint ""
		(layer "F.Cu")
		(at 341.372444 -343.952322 90)
		(property "Reference" "C524"
			(at 0 0 90)
			(layer "F.SilkS")
			(hide yes)
			(effects
				(font
					(size 1.27 1.27)
				)
			)
		)
		(property "Value" ""
			(at 0 0 90)
			(layer "F.Fab")
			(effects
				(font
					(size 1.27 1.27)
				)
			)
		)
		(duplicate_pad_numbers_are_jumpers no)
		(fp_line
			(start 0.299974 -0.150114)
			(end 0.299974 0.150114)
			(stroke
				(width 0.1)
				(type default)
			)
			(layer "F.Fab")
		)
		(fp_line
			(start -0.299974 -0.150114)
			(end 0.299974 -0.150114)
			(stroke
				(width 0.1)
				(type default)
			)
			(layer "F.Fab")
		)
		(fp_line
			(start 0.299974 0.150114)
			(end -0.299974 0.150114)
			(stroke
				(width 0.1)
				(type default)
			)
			(layer "F.Fab")
		)
		(fp_line
			(start -0.299974 0.150114)
			(end -0.299974 -0.150114)
			(stroke
				(width 0.1)
				(type default)
			)
			(layer "F.Fab")
		)
		(pad "1" smd rect
			(at -0.2667 0 90)
			(size 0.3048 0.381)
			(layers "F.Cu" "F.Mask" "F.Paste")
			(net "P5E_PEX2_STN5_TX_DN<93>")
		)
		(pad "2" smd rect
			(at 0.2667 0 90)
			(size 0.3048 0.381)
			(layers "F.Cu" "F.Mask" "F.Paste")
			(net "P5E_PEX2_STN5_TX_C_DN<93>")
		)
	)
	(footprint ""
		(layer "F.Cu")
		(at 95.475044 -194.183 180)
		(property "Reference" "R6626"
			(at 0 0 180)
			(layer "F.SilkS")
			(hide yes)
			(effects
				(font
					(size 1.27 1.27)
				)
			)
		)
		(property "Value" ""
			(at 0 0 180)
			(layer "F.Fab")
			(effects
				(font
					(size 1.27 1.27)
				)
			)
		)
		(duplicate_pad_numbers_are_jumpers no)
		(fp_line
			(start 0.7874 0.4064)
			(end -0.7874 0.4064)
			(stroke
				(width 0.1524)
				(type default)
			)
			(layer "F.SilkS")
		)
		(fp_line
			(start 0.7874 -0.4064)
			(end 0.7874 0.4064)
			(stroke
				(width 0.1524)
				(type default)
			)
			(layer "F.SilkS")
		)
		(fp_line
			(start -0.7874 0.4064)
			(end -0.7874 -0.4064)
			(stroke
				(width 0.1524)
				(type default)
			)
			(layer "F.SilkS")
		)
		(fp_line
			(start -0.7874 -0.4064)
			(end 0.7874 -0.4064)
			(stroke
				(width 0.1524)
				(type default)
			)
			(layer "F.SilkS")
		)
		(fp_line
			(start 0.67945 0.3048)
			(end 0.120396 0.3048)
			(stroke
				(width 0.1)
				(type default)
			)
			(layer "F.Fab")
		)
		(fp_line
			(start 0.67945 -0.3048)
			(end 0.67945 0.3048)
			(stroke
				(width 0.1)
				(type default)
			)
			(layer "F.Fab")
		)
		(fp_line
			(start 0.12065 -0.2794)
			(end 0.12065 -0.3048)
			(stroke
				(width 0.1)
				(type default)
			)
			(layer "F.Fab")
		)
		(fp_line
			(start 0.12065 -0.3048)
			(end 0.67945 -0.3048)
			(stroke
				(width 0.1)
				(type default)
			)
			(layer "F.Fab")
		)
		(fp_line
			(start 0.120396 0.3048)
			(end 0.120396 0.2794)
			(stroke
				(width 0.1)
				(type default)
			)
			(layer "F.Fab")
		)
		(fp_line
			(start 0.120396 0.2794)
			(end -0.12065 0.2794)
			(stroke
				(width 0.1)
				(type default)
			)
			(layer "F.Fab")
		)
		(fp_line
			(start -0.12065 0.3048)
			(end -0.67945 0.3048)
			(stroke
				(width 0.1)
				(type default)
			)
			(layer "F.Fab")
		)
		(fp_line
			(start -0.12065 0.2794)
			(end -0.12065 0.3048)
			(stroke
				(width 0.1)
				(type default)
			)
			(layer "F.Fab")
		)
		(fp_line
			(start -0.12065 -0.2794)
			(end 0.12065 -0.2794)
			(stroke
				(width 0.1)
				(type default)
			)
			(layer "F.Fab")
		)
		(fp_line
			(start -0.12065 -0.305054)
			(end -0.12065 -0.2794)
			(stroke
				(width 0.1)
				(type default)
			)
			(layer "F.Fab")
		)
		(fp_line
			(start -0.67945 0.3048)
			(end -0.67945 -0.305054)
			(stroke
				(width 0.1)
				(type default)
			)
			(layer "F.Fab")
		)
		(fp_line
			(start -0.67945 -0.305054)
			(end -0.12065 -0.305054)
			(stroke
				(width 0.1)
				(type default)
			)
			(layer "F.Fab")
		)
		(pad "1" smd circle
			(at -0.40005 0 180)
			(size 0 0)
			(layers "F.Cu" "F.Mask" "F.Paste")
			(net "UART_PEX3_CLI_CP2108_RX")
		)
		(pad "2" smd circle
			(at 0.40005 0 180)
			(size 0 0)
			(layers "F.Cu" "F.Mask" "F.Paste")
			(net "UART_PEX3_CLI_R_RX")
		)
	)
)
